(kicad_pcb
	(version 20260206)
	(generator "pcbnew")
	(generator_version "10.0")
	(general
		(thickness 1.6)
		(legacy_teardrops no)
	)
	(paper "A4")
	(title_block
		(title "01162023_DA0F0TEBIF0_F0T_Expander_BD_F_brd_V02_OCP.brd")
		(comment 1 "Grand Teton / footprints 8063-8070 of 9728")
	)
	(layers
		(0 "F.Cu" signal "TOP")
		(4 "In1.Cu" signal "GND")
		(6 "In2.Cu" signal "VCC")
		(8 "In3.Cu" signal "VCC1")
		(10 "In4.Cu" signal "GND1")
		(12 "In5.Cu" signal "IN1")
		(14 "In6.Cu" signal "GND2")
		(16 "In7.Cu" signal "IN2")
		(18 "In8.Cu" signal "GND3")
		(20 "In9.Cu" signal "IN3")
		(22 "In10.Cu" signal "GND4")
		(24 "In11.Cu" signal "IN4")
		(26 "In12.Cu" signal "GND5")
		(28 "In13.Cu" signal "IN5")
		(30 "In14.Cu" signal "GND6")
		(32 "In15.Cu" signal "IN6")
		(34 "In16.Cu" signal "GND7")
		(2 "B.Cu" signal "BOTTOM")
		(9 "F.Adhes" user "F.Adhesive")
		(11 "B.Adhes" user "B.Adhesive")
		(13 "F.Paste" user "Package Geometry/Pastemask Top")
		(15 "B.Paste" user "Package Geometry/Pastemask Bottom")
		(5 "F.SilkS" user "Ref Des/Silkscreen Top")
		(7 "B.SilkS" user "Ref Des/Silkscreen Bottom")
		(1 "F.Mask" user "Board Geometry/Soldermask Top")
		(3 "B.Mask" user "Board Geometry/Soldermask Bottom")
		(17 "Dwgs.User" user "User.Drawings")
		(19 "Cmts.User" user "User.Comments")
		(21 "Eco1.User" user "User.Eco1")
		(23 "Eco2.User" user "User.Eco2")
		(25 "Edge.Cuts" user "Board Geometry/Outline")
		(27 "Margin" user)
		(31 "F.CrtYd" user "Package Geometry/Place Bound Top")
		(29 "B.CrtYd" user "Package Geometry/Place Bound Bottom")
		(35 "F.Fab" user "Ref Des/Assembly Top")
		(33 "B.Fab" user "Ref Des/Assembly Bottom")
	)
	(footprint ""
		(layer "B.Cu")
		(at 297.549824 -290.199826 90)
		(property "Reference" "C1678"
			(at 0 0 90)
			(layer "B.SilkS")
			(hide yes)
			(effects
				(font
					(size 1.27 1.27)
				)
				(justify mirror)
			)
		)
		(property "Value" ""
			(at 0 0 90)
			(layer "B.Fab")
			(effects
				(font
					(size 1.27 1.27)
				)
				(justify mirror)
			)
		)
		(duplicate_pad_numbers_are_jumpers no)
		(fp_line
			(start 0.299974 -0.150114)
			(end -0.299974 -0.150114)
			(stroke
				(width 0.1)
				(type default)
			)
			(layer "B.Fab")
		)
		(fp_line
			(start -0.299974 -0.150114)
			(end -0.299974 0.150114)
			(stroke
				(width 0.1)
				(type default)
			)
			(layer "B.Fab")
		)
		(fp_line
			(start 0.299974 0.150114)
			(end 0.299974 -0.150114)
			(stroke
				(width 0.1)
				(type default)
			)
			(layer "B.Fab")
		)
		(fp_line
			(start -0.299974 0.150114)
			(end 0.299974 0.150114)
			(stroke
				(width 0.1)
				(type default)
			)
			(layer "B.Fab")
		)
		(pad "1" smd rect
			(at 0.2667 0 270)
			(size 0.3048 0.381)
			(layers "B.Cu" "B.Mask" "B.Paste")
			(net "P0V8_SERDES_VDDA_PEX2")
		)
		(pad "2" smd rect
			(at -0.2667 0 270)
			(size 0.3048 0.381)
			(layers "B.Cu" "B.Mask" "B.Paste")
			(net "GND")
		)
	)
	(footprint ""
		(layer "B.Cu")
		(at 160.549844 -294.94988)
		(property "Reference" "C3179"
			(at 0 0 0)
			(layer "B.SilkS")
			(hide yes)
			(effects
				(font
					(size 1.27 1.27)
				)
				(justify mirror)
			)
		)
		(property "Value" ""
			(at 0 0 0)
			(layer "B.Fab")
			(effects
				(font
					(size 1.27 1.27)
				)
				(justify mirror)
			)
		)
		(duplicate_pad_numbers_are_jumpers no)
		(fp_line
			(start -0.299974 -0.150114)
			(end -0.299974 0.150114)
			(stroke
				(width 0.1)
				(type default)
			)
			(layer "B.Fab")
		)
		(fp_line
			(start -0.299974 0.150114)
			(end 0.299974 0.150114)
			(stroke
				(width 0.1)
				(type default)
			)
			(layer "B.Fab")
		)
		(fp_line
			(start 0.299974 -0.150114)
			(end -0.299974 -0.150114)
			(stroke
				(width 0.1)
				(type default)
			)
			(layer "B.Fab")
		)
		(fp_line
			(start 0.299974 0.150114)
			(end 0.299974 -0.150114)
			(stroke
				(width 0.1)
				(type default)
			)
			(layer "B.Fab")
		)
		(pad "1" smd rect
			(at 0.2667 0 180)
			(size 0.3048 0.381)
			(layers "B.Cu" "B.Mask" "B.Paste")
			(net "P1V8_PEX")
		)
		(pad "2" smd rect
			(at -0.2667 0 180)
			(size 0.3048 0.381)
			(layers "B.Cu" "B.Mask" "B.Paste")
			(net "GND")
		)
	)
	(footprint ""
		(layer "B.Cu")
		(at 60.151264 -305.399948 -90)
		(property "Reference" "C2975"
			(at 0 0 90)
			(layer "B.SilkS")
			(hide yes)
			(effects
				(font
					(size 1.27 1.27)
				)
				(justify mirror)
			)
		)
		(property "Value" ""
			(at 0 0 90)
			(layer "B.Fab")
			(effects
				(font
					(size 1.27 1.27)
				)
				(justify mirror)
			)
		)
		(duplicate_pad_numbers_are_jumpers no)
		(fp_line
			(start -0.299974 0.150114)
			(end 0.299974 0.150114)
			(stroke
				(width 0.1)
				(type default)
			)
			(layer "B.Fab")
		)
		(fp_line
			(start 0.299974 0.150114)
			(end 0.299974 -0.150114)
			(stroke
				(width 0.1)
				(type default)
			)
			(layer "B.Fab")
		)
		(fp_line
			(start -0.299974 -0.150114)
			(end -0.299974 0.150114)
			(stroke
				(width 0.1)
				(type default)
			)
			(layer "B.Fab")
		)
		(fp_line
			(start 0.299974 -0.150114)
			(end -0.299974 -0.150114)
			(stroke
				(width 0.1)
				(type default)
			)
			(layer "B.Fab")
		)
		(pad "1" smd rect
			(at 0.2667 0 90)
			(size 0.3048 0.381)
			(layers "B.Cu" "B.Mask" "B.Paste")
			(net "P1V25_SERDES_VDDPLL_PEX0")
		)
		(pad "2" smd rect
			(at -0.2667 0 90)
			(size 0.3048 0.381)
			(layers "B.Cu" "B.Mask" "B.Paste")
			(net "GND")
		)
	)
	(footprint ""
		(layer "B.Cu")
		(at 161.964116 -144.421352 180)
		(property "Reference" "C880"
			(at 0 0 0)
			(layer "B.SilkS")
			(hide yes)
			(effects
				(font
					(size 1.27 1.27)
				)
				(justify mirror)
			)
		)
		(property "Value" ""
			(at 0 0 0)
			(layer "B.Fab")
			(effects
				(font
					(size 1.27 1.27)
				)
				(justify mirror)
			)
		)
		(duplicate_pad_numbers_are_jumpers no)
		(fp_line
			(start 0.299974 0.150114)
			(end 0.299974 -0.150114)
			(stroke
				(width 0.1)
				(type default)
			)
			(layer "B.Fab")
		)
		(fp_line
			(start 0.299974 -0.150114)
			(end -0.299974 -0.150114)
			(stroke
				(width 0.1)
				(type default)
			)
			(layer "B.Fab")
		)
		(fp_line
			(start -0.299974 0.150114)
			(end 0.299974 0.150114)
			(stroke
				(width 0.1)
				(type default)
			)
			(layer "B.Fab")
		)
		(fp_line
			(start -0.299974 -0.150114)
			(end -0.299974 0.150114)
			(stroke
				(width 0.1)
				(type default)
			)
			(layer "B.Fab")
		)
		(pad "1" smd rect
			(at 0.2667 0)
			(size 0.3048 0.381)
			(layers "B.Cu" "B.Mask" "B.Paste")
			(net "P12V_NIC2")
		)
		(pad "2" smd rect
			(at -0.2667 0)
			(size 0.3048 0.381)
			(layers "B.Cu" "B.Mask" "B.Paste")
			(net "GND")
		)
	)
	(footprint ""
		(layer "B.Cu")
		(at 281.755342 -151.9936)
		(property "Reference" "R222"
			(at 0 0 0)
			(layer "B.SilkS")
			(hide yes)
			(effects
				(font
					(size 1.27 1.27)
				)
				(justify mirror)
			)
		)
		(property "Value" ""
			(at 0 0 0)
			(layer "B.Fab")
			(effects
				(font
					(size 1.27 1.27)
				)
				(justify mirror)
			)
		)
		(duplicate_pad_numbers_are_jumpers no)
		(fp_line
			(start -0.7874 -0.4064)
			(end -0.7874 0.4064)
			(stroke
				(width 0.1524)
				(type default)
			)
			(layer "B.SilkS")
		)
		(fp_line
			(start -0.7874 0.4064)
			(end 0.7874 0.4064)
			(stroke
				(width 0.1524)
				(type default)
			)
			(layer "B.SilkS")
		)
		(fp_line
			(start 0.7874 -0.4064)
			(end -0.7874 -0.4064)
			(stroke
				(width 0.1524)
				(type default)
			)
			(layer "B.SilkS")
		)
		(fp_line
			(start 0.7874 0.4064)
			(end 0.7874 -0.4064)
			(stroke
				(width 0.1524)
				(type default)
			)
			(layer "B.SilkS")
		)
		(fp_line
			(start -0.67945 -0.3048)
			(end -0.67945 0.3048)
			(stroke
				(width 0.1)
				(type default)
			)
			(layer "B.Fab")
		)
		(fp_line
			(start -0.67945 0.3048)
			(end -0.120396 0.3048)
			(stroke
				(width 0.1)
				(type default)
			)
			(layer "B.Fab")
		)
		(fp_line
			(start -0.12065 -0.3048)
			(end -0.67945 -0.3048)
			(stroke
				(width 0.1)
				(type default)
			)
			(layer "B.Fab")
		)
		(fp_line
			(start -0.12065 -0.2794)
			(end -0.12065 -0.3048)
			(stroke
				(width 0.1)
				(type default)
			)
			(layer "B.Fab")
		)
		(fp_line
			(start -0.120396 0.2794)
			(end 0.12065 0.2794)
			(stroke
				(width 0.1)
				(type default)
			)
			(layer "B.Fab")
		)
		(fp_line
			(start -0.120396 0.3048)
			(end -0.120396 0.2794)
			(stroke
				(width 0.1)
				(type default)
			)
			(layer "B.Fab")
		)
		(fp_line
			(start 0.12065 -0.305054)
			(end 0.12065 -0.2794)
			(stroke
				(width 0.1)
				(type default)
			)
			(layer "B.Fab")
		)
		(fp_line
			(start 0.12065 -0.2794)
			(end -0.12065 -0.2794)
			(stroke
				(width 0.1)
				(type default)
			)
			(layer "B.Fab")
		)
		(fp_line
			(start 0.12065 0.2794)
			(end 0.12065 0.3048)
			(stroke
				(width 0.1)
				(type default)
			)
			(layer "B.Fab")
		)
		(fp_line
			(start 0.12065 0.3048)
			(end 0.67945 0.3048)
			(stroke
				(width 0.1)
				(type default)
			)
			(layer "B.Fab")
		)
		(fp_line
			(start 0.67945 -0.305054)
			(end 0.12065 -0.305054)
			(stroke
				(width 0.1)
				(type default)
			)
			(layer "B.Fab")
		)
		(fp_line
			(start 0.67945 0.3048)
			(end 0.67945 -0.305054)
			(stroke
				(width 0.1)
				(type default)
			)
			(layer "B.Fab")
		)
		(pad "1" smd circle
			(at 0.40005 0 180)
			(size 0 0)
			(layers "B.Cu" "B.Mask" "B.Paste")
			(net "NCSI_NIC4_TXD0")
		)
		(pad "2" smd circle
			(at -0.40005 0 180)
			(size 0 0)
			(layers "B.Cu" "B.Mask" "B.Paste")
			(net "GND")
		)
	)
	(footprint ""
		(layer "B.Cu")
		(at 140.37691 -214.964772 -90)
		(property "Reference" "R993"
			(at 0 0 90)
			(layer "B.SilkS")
			(hide yes)
			(effects
				(font
					(size 1.27 1.27)
				)
				(justify mirror)
			)
		)
		(property "Value" ""
			(at 0 0 90)
			(layer "B.Fab")
			(effects
				(font
					(size 1.27 1.27)
				)
				(justify mirror)
			)
		)
		(duplicate_pad_numbers_are_jumpers no)
		(fp_line
			(start -0.7874 0.4064)
			(end 0.7874 0.4064)
			(stroke
				(width 0.1524)
				(type default)
			)
			(layer "B.SilkS")
		)
		(fp_line
			(start 0.7874 0.4064)
			(end 0.7874 -0.4064)
			(stroke
				(width 0.1524)
				(type default)
			)
			(layer "B.SilkS")
		)
		(fp_line
			(start -0.7874 -0.4064)
			(end -0.7874 0.4064)
			(stroke
				(width 0.1524)
				(type default)
			)
			(layer "B.SilkS")
		)
		(fp_line
			(start 0.7874 -0.4064)
			(end -0.7874 -0.4064)
			(stroke
				(width 0.1524)
				(type default)
			)
			(layer "B.SilkS")
		)
		(fp_line
			(start -0.67945 0.3048)
			(end -0.120396 0.3048)
			(stroke
				(width 0.1)
				(type default)
			)
			(layer "B.Fab")
		)
		(fp_line
			(start -0.120396 0.3048)
			(end -0.120396 0.2794)
			(stroke
				(width 0.1)
				(type default)
			)
			(layer "B.Fab")
		)
		(fp_line
			(start 0.12065 0.3048)
			(end 0.67945 0.3048)
			(stroke
				(width 0.1)
				(type default)
			)
			(layer "B.Fab")
		)
		(fp_line
			(start 0.67945 0.3048)
			(end 0.67945 -0.305054)
			(stroke
				(width 0.1)
				(type default)
			)
			(layer "B.Fab")
		)
		(fp_line
			(start -0.120396 0.2794)
			(end 0.12065 0.2794)
			(stroke
				(width 0.1)
				(type default)
			)
			(layer "B.Fab")
		)
		(fp_line
			(start 0.12065 0.2794)
			(end 0.12065 0.3048)
			(stroke
				(width 0.1)
				(type default)
			)
			(layer "B.Fab")
		)
		(fp_line
			(start -0.12065 -0.2794)
			(end -0.12065 -0.3048)
			(stroke
				(width 0.1)
				(type default)
			)
			(layer "B.Fab")
		)
		(fp_line
			(start 0.12065 -0.2794)
			(end -0.12065 -0.2794)
			(stroke
				(width 0.1)
				(type default)
			)
			(layer "B.Fab")
		)
		(fp_line
			(start -0.67945 -0.3048)
			(end -0.67945 0.3048)
			(stroke
				(width 0.1)
				(type default)
			)
			(layer "B.Fab")
		)
		(fp_line
			(start -0.12065 -0.3048)
			(end -0.67945 -0.3048)
			(stroke
				(width 0.1)
				(type default)
			)
			(layer "B.Fab")
		)
		(fp_line
			(start 0.12065 -0.305054)
			(end 0.12065 -0.2794)
			(stroke
				(width 0.1)
				(type default)
			)
			(layer "B.Fab")
		)
		(fp_line
			(start 0.67945 -0.305054)
			(end 0.12065 -0.305054)
			(stroke
				(width 0.1)
				(type default)
			)
			(layer "B.Fab")
		)
		(pad "1" smd circle
			(at 0.40005 0 90)
			(size 0 0)
			(layers "B.Cu" "B.Mask" "B.Paste")
			(net "UART_PEX3_CLI_BUF_R_RX")
		)
		(pad "2" smd circle
			(at -0.40005 0 90)
			(size 0 0)
			(layers "B.Cu" "B.Mask" "B.Paste")
			(net "UART_PEX3_CLI_BUF_RX")
		)
	)
	(footprint ""
		(layer "B.Cu")
		(at 366.268 -236.601)
		(property "Reference" "R915"
			(at 0 0 0)
			(layer "B.SilkS")
			(hide yes)
			(effects
				(font
					(size 1.27 1.27)
				)
				(justify mirror)
			)
		)
		(property "Value" ""
			(at 0 0 0)
			(layer "B.Fab")
			(effects
				(font
					(size 1.27 1.27)
				)
				(justify mirror)
			)
		)
		(duplicate_pad_numbers_are_jumpers no)
		(fp_line
			(start -0.7874 -0.4064)
			(end -0.7874 0.4064)
			(stroke
				(width 0.1524)
				(type default)
			)
			(layer "B.SilkS")
		)
		(fp_line
			(start -0.7874 0.4064)
			(end 0.7874 0.4064)
			(stroke
				(width 0.1524)
				(type default)
			)
			(layer "B.SilkS")
		)
		(fp_line
			(start 0.7874 -0.4064)
			(end -0.7874 -0.4064)
			(stroke
				(width 0.1524)
				(type default)
			)
			(layer "B.SilkS")
		)
		(fp_line
			(start 0.7874 0.4064)
			(end 0.7874 -0.4064)
			(stroke
				(width 0.1524)
				(type default)
			)
			(layer "B.SilkS")
		)
		(fp_line
			(start -0.67945 -0.3048)
			(end -0.67945 0.3048)
			(stroke
				(width 0.1)
				(type default)
			)
			(layer "B.Fab")
		)
		(fp_line
			(start -0.67945 0.3048)
			(end -0.120396 0.3048)
			(stroke
				(width 0.1)
				(type default)
			)
			(layer "B.Fab")
		)
		(fp_line
			(start -0.12065 -0.3048)
			(end -0.67945 -0.3048)
			(stroke
				(width 0.1)
				(type default)
			)
			(layer "B.Fab")
		)
		(fp_line
			(start -0.12065 -0.2794)
			(end -0.12065 -0.3048)
			(stroke
				(width 0.1)
				(type default)
			)
			(layer "B.Fab")
		)
		(fp_line
			(start -0.120396 0.2794)
			(end 0.12065 0.2794)
			(stroke
				(width 0.1)
				(type default)
			)
			(layer "B.Fab")
		)
		(fp_line
			(start -0.120396 0.3048)
			(end -0.120396 0.2794)
			(stroke
				(width 0.1)
				(type default)
			)
			(layer "B.Fab")
		)
		(fp_line
			(start 0.12065 -0.305054)
			(end 0.12065 -0.2794)
			(stroke
				(width 0.1)
				(type default)
			)
			(layer "B.Fab")
		)
		(fp_line
			(start 0.12065 -0.2794)
			(end -0.12065 -0.2794)
			(stroke
				(width 0.1)
				(type default)
			)
			(layer "B.Fab")
		)
		(fp_line
			(start 0.12065 0.2794)
			(end 0.12065 0.3048)
			(stroke
				(width 0.1)
				(type default)
			)
			(layer "B.Fab")
		)
		(fp_line
			(start 0.12065 0.3048)
			(end 0.67945 0.3048)
			(stroke
				(width 0.1)
				(type default)
			)
			(layer "B.Fab")
		)
		(fp_line
			(start 0.67945 -0.305054)
			(end 0.12065 -0.305054)
			(stroke
				(width 0.1)
				(type default)
			)
			(layer "B.Fab")
		)
		(fp_line
			(start 0.67945 0.3048)
			(end 0.67945 -0.305054)
			(stroke
				(width 0.1)
				(type default)
			)
			(layer "B.Fab")
		)
		(pad "1" smd circle
			(at 0.40005 0 180)
			(size 0 0)
			(layers "B.Cu" "B.Mask" "B.Paste")
			(net "FT4232_SDB_EEPROM_R_SDA")
		)
		(pad "2" smd circle
			(at -0.40005 0 180)
			(size 0 0)
			(layers "B.Cu" "B.Mask" "B.Paste")
			(net "FT4232_SDB_EEPROM_DO")
		)
	)
	(footprint ""
		(layer "B.Cu")
		(at 114.450114 -258.004564 -90)
		(property "Reference" "PC54"
			(at 0 0 90)
			(layer "B.SilkS")
			(hide yes)
			(effects
				(font
					(size 1.27 1.27)
				)
				(justify mirror)
			)
		)
		(property "Value" ""
			(at 0 0 90)
			(layer "B.Fab")
			(effects
				(font
					(size 1.27 1.27)
				)
				(justify mirror)
			)
		)
		(duplicate_pad_numbers_are_jumpers no)
		(fp_line
			(start -0.7874 0.4064)
			(end 0.7874 0.4064)
			(stroke
				(width 0.1524)
				(type default)
			)
			(layer "B.SilkS")
		)
		(fp_line
			(start 0.7874 0.4064)
			(end 0.7874 -0.4064)
			(stroke
				(width 0.1524)
				(type default)
			)
			(layer "B.SilkS")
		)
		(fp_line
			(start -0.7874 -0.4064)
			(end -0.7874 0.4064)
			(stroke
				(width 0.1524)
				(type default)
			)
			(layer "B.SilkS")
		)
		(fp_line
			(start 0.7874 -0.4064)
			(end -0.7874 -0.4064)
			(stroke
				(width 0.1524)
				(type default)
			)
			(layer "B.SilkS")
		)
		(fp_line
			(start -0.67945 0.3048)
			(end -0.120396 0.3048)
			(stroke
				(width 0.1)
				(type default)
			)
			(layer "B.Fab")
		)
		(fp_line
			(start -0.120396 0.3048)
			(end -0.120396 0.2794)
			(stroke
				(width 0.1)
				(type default)
			)
			(layer "B.Fab")
		)
		(fp_line
			(start 0.12065 0.3048)
			(end 0.67945 0.3048)
			(stroke
				(width 0.1)
				(type default)
			)
			(layer "B.Fab")
		)
		(fp_line
			(start 0.67945 0.3048)
			(end 0.67945 -0.305054)
			(stroke
				(width 0.1)
				(type default)
			)
			(layer "B.Fab")
		)
		(fp_line
			(start -0.120396 0.2794)
			(end 0.12065 0.2794)
			(stroke
				(width 0.1)
				(type default)
			)
			(layer "B.Fab")
		)
		(fp_line
			(start 0.12065 0.2794)
			(end 0.12065 0.3048)
			(stroke
				(width 0.1)
				(type default)
			)
			(layer "B.Fab")
		)
		(fp_line
			(start -0.12065 -0.2794)
			(end -0.12065 -0.3048)
			(stroke
				(width 0.1)
				(type default)
			)
			(layer "B.Fab")
		)
		(fp_line
			(start 0.12065 -0.2794)
			(end -0.12065 -0.2794)
			(stroke
				(width 0.1)
				(type default)
			)
			(layer "B.Fab")
		)
		(fp_line
			(start -0.67945 -0.3048)
			(end -0.67945 0.3048)
			(stroke
				(width 0.1)
				(type default)
			)
			(layer "B.Fab")
		)
		(fp_line
			(start -0.12065 -0.3048)
			(end -0.67945 -0.3048)
			(stroke
				(width 0.1)
				(type default)
			)
			(layer "B.Fab")
		)
		(fp_line
			(start 0.12065 -0.305054)
			(end 0.12065 -0.2794)
			(stroke
				(width 0.1)
				(type default)
			)
			(layer "B.Fab")
		)
		(fp_line
			(start 0.67945 -0.305054)
			(end 0.12065 -0.305054)
			(stroke
				(width 0.1)
				(type default)
			)
			(layer "B.Fab")
		)
		(pad "1" smd circle
			(at 0.40005 0 90)
			(size 0 0)
			(layers "B.Cu" "B.Mask" "B.Paste")
			(net "P0V8_PEX0_IINSEN")
		)
		(pad "2" smd circle
			(at -0.40005 0 90)
			(size 0 0)
			(layers "B.Cu" "B.Mask" "B.Paste")
			(net "GND")
		)
	)
)
